(kicad_pcb
	(version 20260206)
	(generator "pcbnew")
	(generator_version "10.0")
	(general
		(thickness 1.6)
		(legacy_teardrops no)
	)
	(paper "A4")
	(title_block
		(title "Wiwynn_Tioga_Pass_MB.brd")
		(comment 1 "Tioga Pass / footprints 3698-3705 of 4770")
	)
	(layers
		(0 "F.Cu" signal "TOP")
		(4 "In1.Cu" signal "L2GND")
		(6 "In2.Cu" signal "L3")
		(8 "In3.Cu" signal "L4GND")
		(10 "In4.Cu" signal "L5")
		(12 "In5.Cu" signal "L6GND")
		(14 "In6.Cu" signal "L7VCC")
		(16 "In7.Cu" signal "L8VCC")
		(18 "In8.Cu" signal "L9GND")
		(20 "In9.Cu" signal "L10")
		(22 "In10.Cu" signal "L11GND")
		(24 "In11.Cu" signal "L12")
		(26 "In12.Cu" signal "L13GND")
		(2 "B.Cu" signal "BOTTOM")
		(9 "F.Adhes" user "F.Adhesive")
		(11 "B.Adhes" user "B.Adhesive")
		(13 "F.Paste" user "Package Geometry/Pastemask Top")
		(15 "B.Paste" user "Package Geometry/Pastemask Bottom")
		(5 "F.SilkS" user "Ref Des/Silkscreen Top")
		(7 "B.SilkS" user "Ref Des/Silkscreen Bottom")
		(1 "F.Mask" user "Board Geometry/Soldermask Top")
		(3 "B.Mask" user "Board Geometry/Soldermask Bottom")
		(17 "Dwgs.User" user "User.Drawings")
		(19 "Cmts.User" user "User.Comments")
		(21 "Eco1.User" user "User.Eco1")
		(23 "Eco2.User" user "User.Eco2")
		(25 "Edge.Cuts" user "Board Geometry/Outline")
		(27 "Margin" user)
		(31 "F.CrtYd" user "Package Geometry/Place Bound Top")
		(29 "B.CrtYd" user "Package Geometry/Place Bound Bottom")
		(35 "F.Fab" user "Ref Des/Assembly Top")
		(33 "B.Fab" user "Ref Des/Assembly Bottom")
	)
	(footprint ""
		(layer "B.Cu")
		(at 266.397232 -149.8092 90)
		(property "Reference" "C5G69"
			(at -1.14681 0.76708 180)
			(unlocked yes)
			(layer "B.SilkS")
			(effects
				(font
					(size 0.7874 0.5842)
					(thickness 0.1524)
				)
				(justify mirror)
			)
		)
		(property "Value" ""
			(at 0 0 90)
			(layer "B.Fab")
			(effects
				(font
					(size 1.27 1.27)
				)
				(justify mirror)
			)
		)
		(duplicate_pad_numbers_are_jumpers no)
		(fp_rect
			(start -0.4953 -0.2032)
			(end 0.4953 1.6002)
			(stroke
				(width 0)
				(type default)
			)
			(fill no)
			(layer "B.CrtYd")
		)
		(fp_line
			(start 0.4953 -0.2032)
			(end -0.4953 -0.2032)
			(stroke
				(width 0.1)
				(type default)
			)
			(layer "B.Fab")
		)
		(fp_line
			(start -0.4953 -0.2032)
			(end -0.4953 1.6002)
			(stroke
				(width 0.1)
				(type default)
			)
			(layer "B.Fab")
		)
		(fp_line
			(start 0.4953 1.6002)
			(end 0.4953 -0.2032)
			(stroke
				(width 0.1)
				(type default)
			)
			(layer "B.Fab")
		)
		(fp_line
			(start -0.4953 1.6002)
			(end 0.4953 1.6002)
			(stroke
				(width 0.1)
				(type default)
			)
			(layer "B.Fab")
		)
		(pad "1" smd rect
			(at 0 0 270)
			(size 0.762 0.889)
			(layers "B.Cu" "B.Mask" "B.Paste")
			(net "PVDDQ_DEF")
		)
		(pad "2" smd rect
			(at 0 1.397 270)
			(size 0.762 0.889)
			(layers "B.Cu" "B.Mask" "B.Paste")
			(net "GND")
		)
		(zone
			(layer "B.Cu")
			(hatch none 0.5)
			(connect_pads
				(clearance 0)
			)
			(min_thickness 0.25)
			(keepout
				(tracks not_allowed)
				(vias allowed)
				(pads allowed)
				(copperpour not_allowed)
				(footprints allowed)
			)
			(placement
				(enabled no)
				(sheetname "")
			)
			(fill
				(thermal_gap 0.5)
				(thermal_bridge_width 0.5)
				(island_removal_mode 0)
			)
			(polygon
				(pts
					(xy 266.841732 -149.4282) (xy 267.349732 -149.4282) (xy 267.349732 -150.1902) (xy 266.841732 -150.1902)
				)
			)
		)
	)
	(footprint ""
		(layer "B.Cu")
		(at 164.973 -69.088 -90)
		(property "Reference" "R6P33"
			(at 0 0 90)
			(layer "B.SilkS")
			(hide yes)
			(effects
				(font
					(size 1.27 1.27)
				)
				(justify mirror)
			)
		)
		(property "Value" ""
			(at 0 0 90)
			(layer "B.Fab")
			(effects
				(font
					(size 1.27 1.27)
				)
				(justify mirror)
			)
		)
		(duplicate_pad_numbers_are_jumpers no)
		(fp_poly
			(pts
				(xy 0.2794 -0.1016) (xy -0.2794 -0.1016) (xy -0.2794 0.9906) (xy 0.2794 0.9906)
			)
			(stroke
				(width 0)
				(type default)
			)
			(fill no)
			(layer "B.CrtYd")
		)
		(fp_line
			(start -0.2794 0.9906)
			(end -0.2794 -0.1016)
			(stroke
				(width 0.1)
				(type default)
			)
			(layer "B.Fab")
		)
		(fp_line
			(start 0.2794 0.9906)
			(end -0.2794 0.9906)
			(stroke
				(width 0.1)
				(type default)
			)
			(layer "B.Fab")
		)
		(fp_line
			(start -0.2794 -0.1016)
			(end 0.2794 -0.1016)
			(stroke
				(width 0.1)
				(type default)
			)
			(layer "B.Fab")
		)
		(fp_line
			(start 0.2794 -0.1016)
			(end 0.2794 0.9906)
			(stroke
				(width 0.1)
				(type default)
			)
			(layer "B.Fab")
		)
		(pad "1" smd rect
			(at 0 0 90)
			(size 0.508 0.508)
			(layers "B.Cu" "B.Mask" "B.Paste")
			(net "PVCCIO_CPU1")
		)
		(pad "2" smd rect
			(at 0 0.889 90)
			(size 0.508 0.508)
			(layers "B.Cu" "B.Mask" "B.Paste")
			(net "SVID_CLK0_CPU1_R")
		)
		(zone
			(layer "B.Cu")
			(hatch none 0.5)
			(connect_pads
				(clearance 0)
			)
			(min_thickness 0.25)
			(keepout
				(tracks not_allowed)
				(vias allowed)
				(pads allowed)
				(copperpour not_allowed)
				(footprints allowed)
			)
			(placement
				(enabled no)
				(sheetname "")
			)
			(fill
				(thermal_gap 0.5)
				(thermal_bridge_width 0.5)
				(island_removal_mode 0)
			)
			(polygon
				(pts
					(xy 164.338 -68.834) (xy 164.338 -69.342) (xy 164.719 -69.342) (xy 164.719 -68.834)
				)
			)
		)
		(zone
			(layer "B.Cu")
			(hatch none 0.5)
			(connect_pads
				(clearance 0)
			)
			(min_thickness 0.25)
			(keepout
				(tracks allowed)
				(vias not_allowed)
				(pads allowed)
				(copperpour not_allowed)
				(footprints allowed)
			)
			(placement
				(enabled no)
				(sheetname "")
			)
			(fill
				(thermal_gap 0.5)
				(thermal_bridge_width 0.5)
				(island_removal_mode 0)
			)
			(polygon
				(pts
					(xy 164.719 -68.834) (xy 164.719 -69.342) (xy 164.338 -69.342) (xy 164.338 -68.834)
				)
			)
		)
	)
	(footprint ""
		(layer "B.Cu")
		(at 479.923602 -58.772298 90)
		(property "Reference" "R8E29"
			(at 0 0 90)
			(layer "B.SilkS")
			(hide yes)
			(effects
				(font
					(size 1.27 1.27)
				)
				(justify mirror)
			)
		)
		(property "Value" ""
			(at 0 0 90)
			(layer "B.Fab")
			(effects
				(font
					(size 1.27 1.27)
				)
				(justify mirror)
			)
		)
		(duplicate_pad_numbers_are_jumpers no)
		(fp_poly
			(pts
				(xy 0.2794 -0.1016) (xy -0.2794 -0.1016) (xy -0.2794 0.9906) (xy 0.2794 0.9906)
			)
			(stroke
				(width 0)
				(type default)
			)
			(fill no)
			(layer "B.CrtYd")
		)
		(fp_line
			(start 0.2794 -0.1016)
			(end 0.2794 0.9906)
			(stroke
				(width 0.1)
				(type default)
			)
			(layer "B.Fab")
		)
		(fp_line
			(start -0.2794 -0.1016)
			(end 0.2794 -0.1016)
			(stroke
				(width 0.1)
				(type default)
			)
			(layer "B.Fab")
		)
		(fp_line
			(start 0.2794 0.9906)
			(end -0.2794 0.9906)
			(stroke
				(width 0.1)
				(type default)
			)
			(layer "B.Fab")
		)
		(fp_line
			(start -0.2794 0.9906)
			(end -0.2794 -0.1016)
			(stroke
				(width 0.1)
				(type default)
			)
			(layer "B.Fab")
		)
		(pad "1" smd rect
			(at 0 0 270)
			(size 0.508 0.508)
			(layers "B.Cu" "B.Mask" "B.Paste")
			(net "FM_PE_BMC_WAKE_N")
		)
		(pad "2" smd rect
			(at 0 0.889 270)
			(size 0.508 0.508)
			(layers "B.Cu" "B.Mask" "B.Paste")
			(net "FM_ALL_WAKE_N")
		)
		(zone
			(layer "B.Cu")
			(hatch none 0.5)
			(connect_pads
				(clearance 0)
			)
			(min_thickness 0.25)
			(keepout
				(tracks allowed)
				(vias not_allowed)
				(pads allowed)
				(copperpour not_allowed)
				(footprints allowed)
			)
			(placement
				(enabled no)
				(sheetname "")
			)
			(fill
				(thermal_gap 0.5)
				(thermal_bridge_width 0.5)
				(island_removal_mode 0)
			)
			(polygon
				(pts
					(xy 480.177602 -59.026298) (xy 480.177602 -58.518298) (xy 480.558602 -58.518298) (xy 480.558602 -59.026298)
				)
			)
		)
		(zone
			(layer "B.Cu")
			(hatch none 0.5)
			(connect_pads
				(clearance 0)
			)
			(min_thickness 0.25)
			(keepout
				(tracks not_allowed)
				(vias allowed)
				(pads allowed)
				(copperpour not_allowed)
				(footprints allowed)
			)
			(placement
				(enabled no)
				(sheetname "")
			)
			(fill
				(thermal_gap 0.5)
				(thermal_bridge_width 0.5)
				(island_removal_mode 0)
			)
			(polygon
				(pts
					(xy 480.558602 -59.026298) (xy 480.558602 -58.518298) (xy 480.177602 -58.518298) (xy 480.177602 -59.026298)
				)
			)
		)
	)
	(footprint ""
		(layer "B.Cu")
		(at 488.3404 -42.5196 -90)
		(property "Reference" "C1R22"
			(at 0 0 90)
			(layer "B.SilkS")
			(hide yes)
			(effects
				(font
					(size 1.27 1.27)
				)
				(justify mirror)
			)
		)
		(property "Value" ""
			(at 0 0 90)
			(layer "B.Fab")
			(effects
				(font
					(size 1.27 1.27)
				)
				(justify mirror)
			)
		)
		(duplicate_pad_numbers_are_jumpers no)
		(fp_poly
			(pts
				(xy 0.4953 -0.2032) (xy -0.4953 -0.2032) (xy -0.4953 1.6002) (xy 0.4953 1.6002)
			)
			(stroke
				(width 0)
				(type default)
			)
			(fill no)
			(layer "B.CrtYd")
		)
		(fp_line
			(start -0.4953 1.6002)
			(end 0.4953 1.6002)
			(stroke
				(width 0.1)
				(type default)
			)
			(layer "B.Fab")
		)
		(fp_line
			(start 0.4953 1.6002)
			(end 0.4953 -0.2032)
			(stroke
				(width 0.1)
				(type default)
			)
			(layer "B.Fab")
		)
		(fp_line
			(start -0.4953 -0.2032)
			(end -0.4953 1.6002)
			(stroke
				(width 0.1)
				(type default)
			)
			(layer "B.Fab")
		)
		(fp_line
			(start 0.4953 -0.2032)
			(end -0.4953 -0.2032)
			(stroke
				(width 0.1)
				(type default)
			)
			(layer "B.Fab")
		)
		(pad "1" smd rect
			(at 0 0 90)
			(size 0.762 0.889)
			(layers "B.Cu" "B.Mask" "B.Paste")
			(net "P3V3_STBY")
		)
		(pad "2" smd rect
			(at 0 1.397 90)
			(size 0.762 0.889)
			(layers "B.Cu" "B.Mask" "B.Paste")
			(net "GND")
		)
		(zone
			(layer "B.Cu")
			(hatch none 0.5)
			(connect_pads
				(clearance 0)
			)
			(min_thickness 0.25)
			(keepout
				(tracks not_allowed)
				(vias allowed)
				(pads allowed)
				(copperpour not_allowed)
				(footprints allowed)
			)
			(placement
				(enabled no)
				(sheetname "")
			)
			(fill
				(thermal_gap 0.5)
				(thermal_bridge_width 0.5)
				(island_removal_mode 0)
			)
			(polygon
				(pts
					(xy 487.8959 -42.1386) (xy 487.8959 -42.9006) (xy 487.3879 -42.9006) (xy 487.3879 -42.1386)
				)
			)
		)
	)
	(footprint ""
		(layer "B.Cu")
		(at 164.846 -87.757)
		(property "Reference" "R6P8"
			(at 0 0 0)
			(layer "B.SilkS")
			(hide yes)
			(effects
				(font
					(size 1.27 1.27)
				)
				(justify mirror)
			)
		)
		(property "Value" ""
			(at 0 0 0)
			(layer "B.Fab")
			(effects
				(font
					(size 1.27 1.27)
				)
				(justify mirror)
			)
		)
		(duplicate_pad_numbers_are_jumpers no)
		(fp_poly
			(pts
				(xy 0.2794 -0.1016) (xy -0.2794 -0.1016) (xy -0.2794 0.9906) (xy 0.2794 0.9906)
			)
			(stroke
				(width 0)
				(type default)
			)
			(fill no)
			(layer "B.CrtYd")
		)
		(fp_line
			(start -0.2794 -0.1016)
			(end 0.2794 -0.1016)
			(stroke
				(width 0.1)
				(type default)
			)
			(layer "B.Fab")
		)
		(fp_line
			(start -0.2794 0.9906)
			(end -0.2794 -0.1016)
			(stroke
				(width 0.1)
				(type default)
			)
			(layer "B.Fab")
		)
		(fp_line
			(start 0.2794 -0.1016)
			(end 0.2794 0.9906)
			(stroke
				(width 0.1)
				(type default)
			)
			(layer "B.Fab")
		)
		(fp_line
			(start 0.2794 0.9906)
			(end -0.2794 0.9906)
			(stroke
				(width 0.1)
				(type default)
			)
			(layer "B.Fab")
		)
		(pad "1" smd rect
			(at 0 0 180)
			(size 0.508 0.508)
			(layers "B.Cu" "B.Mask" "B.Paste")
			(net "CLK_100M_CPU1_BCLK1_DN")
		)
		(pad "2" smd rect
			(at 0 0.889 180)
			(size 0.508 0.508)
			(layers "B.Cu" "B.Mask" "B.Paste")
			(net "GND")
		)
		(zone
			(layer "B.Cu")
			(hatch none 0.5)
			(connect_pads
				(clearance 0)
			)
			(min_thickness 0.25)
			(keepout
				(tracks allowed)
				(vias not_allowed)
				(pads allowed)
				(copperpour not_allowed)
				(footprints allowed)
			)
			(placement
				(enabled no)
				(sheetname "")
			)
			(fill
				(thermal_gap 0.5)
				(thermal_bridge_width 0.5)
				(island_removal_mode 0)
			)
			(polygon
				(pts
					(xy 165.1 -87.503) (xy 164.592 -87.503) (xy 164.592 -87.122) (xy 165.1 -87.122)
				)
			)
		)
		(zone
			(layer "B.Cu")
			(hatch none 0.5)
			(connect_pads
				(clearance 0)
			)
			(min_thickness 0.25)
			(keepout
				(tracks not_allowed)
				(vias allowed)
				(pads allowed)
				(copperpour not_allowed)
				(footprints allowed)
			)
			(placement
				(enabled no)
				(sheetname "")
			)
			(fill
				(thermal_gap 0.5)
				(thermal_bridge_width 0.5)
				(island_removal_mode 0)
			)
			(polygon
				(pts
					(xy 165.1 -87.122) (xy 164.592 -87.122) (xy 164.592 -87.503) (xy 165.1 -87.503)
				)
			)
		)
	)
	(footprint ""
		(layer "B.Cu")
		(at 352.96729 -77.915516)
		(property "Reference" "C3P31"
			(at 0 0 0)
			(layer "B.SilkS")
			(hide yes)
			(effects
				(font
					(size 1.27 1.27)
				)
				(justify mirror)
			)
		)
		(property "Value" ""
			(at 0 0 0)
			(layer "B.Fab")
			(effects
				(font
					(size 1.27 1.27)
				)
				(justify mirror)
			)
		)
		(duplicate_pad_numbers_are_jumpers no)
		(fp_poly
			(pts
				(xy -0.3048 -0.1016) (xy -0.3048 0.9906) (xy 0.3048 0.9906) (xy 0.3048 -0.1016)
			)
			(stroke
				(width 0)
				(type default)
			)
			(fill no)
			(layer "B.CrtYd")
		)
		(fp_line
			(start -0.3048 -0.1016)
			(end 0.3048 -0.1016)
			(stroke
				(width 0.1)
				(type default)
			)
			(layer "B.Fab")
		)
		(fp_line
			(start -0.3048 0.9906)
			(end -0.3048 -0.1016)
			(stroke
				(width 0.1)
				(type default)
			)
			(layer "B.Fab")
		)
		(fp_line
			(start 0.3048 -0.1016)
			(end 0.3048 0.9906)
			(stroke
				(width 0.1)
				(type default)
			)
			(layer "B.Fab")
		)
		(fp_line
			(start 0.3048 0.9906)
			(end -0.3048 0.9906)
			(stroke
				(width 0.1)
				(type default)
			)
			(layer "B.Fab")
		)
		(pad "1" smd rect
			(at 0 0 180)
			(size 0.508 0.508)
			(layers "B.Cu" "B.Mask" "B.Paste")
			(net "P3E_CPU0_PE1_SS_TXP<5>")
		)
		(pad "2" smd rect
			(at 0 0.889 180)
			(size 0.508 0.508)
			(layers "B.Cu" "B.Mask" "B.Paste")
			(net "P3E_CPU0_PE1_SS_C_TXP<5>")
		)
		(zone
			(layer "B.Cu")
			(hatch none 0.5)
			(connect_pads
				(clearance 0)
			)
			(min_thickness 0.25)
			(keepout
				(tracks allowed)
				(vias not_allowed)
				(pads allowed)
				(copperpour not_allowed)
				(footprints allowed)
			)
			(placement
				(enabled no)
				(sheetname "")
			)
			(fill
				(thermal_gap 0.5)
				(thermal_bridge_width 0.5)
				(island_removal_mode 0)
			)
			(polygon
				(pts
					(xy 353.22129 -77.661516) (xy 352.71329 -77.661516) (xy 352.71329 -77.280516) (xy 353.22129 -77.280516)
				)
			)
		)
		(zone
			(layer "B.Cu")
			(hatch none 0.5)
			(connect_pads
				(clearance 0)
			)
			(min_thickness 0.25)
			(keepout
				(tracks not_allowed)
				(vias allowed)
				(pads allowed)
				(copperpour not_allowed)
				(footprints allowed)
			)
			(placement
				(enabled no)
				(sheetname "")
			)
			(fill
				(thermal_gap 0.5)
				(thermal_bridge_width 0.5)
				(island_removal_mode 0)
			)
			(polygon
				(pts
					(xy 353.22129 -77.280516) (xy 352.71329 -77.280516) (xy 352.71329 -77.661516) (xy 353.22129 -77.661516)
				)
			)
		)
	)
	(footprint ""
		(layer "B.Cu")
		(at 433.84089 -43.70578 90)
		(property "Reference" "R25W155"
			(at 0.8382 -0.67818 90)
			(unlocked yes)
			(layer "B.SilkS")
			(effects
				(font
					(size 0.4064 0.254)
					(thickness 0.1524)
				)
				(justify left mirror)
			)
		)
		(property "Value" ""
			(at 0 0 90)
			(layer "B.Fab")
			(effects
				(font
					(size 1.27 1.27)
				)
				(justify mirror)
			)
		)
		(duplicate_pad_numbers_are_jumpers no)
		(fp_poly
			(pts
				(xy 0.2794 -0.1016) (xy -0.2794 -0.1016) (xy -0.2794 0.9906) (xy 0.2794 0.9906)
			)
			(stroke
				(width 0)
				(type default)
			)
			(fill no)
			(layer "B.CrtYd")
		)
		(fp_line
			(start 0.2794 -0.1016)
			(end 0.2794 0.9906)
			(stroke
				(width 0.1)
				(type default)
			)
			(layer "B.Fab")
		)
		(fp_line
			(start -0.2794 -0.1016)
			(end 0.2794 -0.1016)
			(stroke
				(width 0.1)
				(type default)
			)
			(layer "B.Fab")
		)
		(fp_line
			(start 0.2794 0.9906)
			(end -0.2794 0.9906)
			(stroke
				(width 0.1)
				(type default)
			)
			(layer "B.Fab")
		)
		(fp_line
			(start -0.2794 0.9906)
			(end -0.2794 -0.1016)
			(stroke
				(width 0.1)
				(type default)
			)
			(layer "B.Fab")
		)
		(pad "1" smd rect
			(at 0 0 270)
			(size 0.508 0.508)
			(layers "B.Cu" "B.Mask" "B.Paste")
			(net "PVCCIO_CPU0")
		)
		(pad "2" smd rect
			(at 0 0.889 270)
			(size 0.508 0.508)
			(layers "B.Cu" "B.Mask" "B.Paste")
			(net "PVCCIO_CPU0_R")
		)
		(zone
			(layer "B.Cu")
			(hatch none 0.5)
			(connect_pads
				(clearance 0)
			)
			(min_thickness 0.25)
			(keepout
				(tracks allowed)
				(vias not_allowed)
				(pads allowed)
				(copperpour not_allowed)
				(footprints allowed)
			)
			(placement
				(enabled no)
				(sheetname "")
			)
			(fill
				(thermal_gap 0.5)
				(thermal_bridge_width 0.5)
				(island_removal_mode 0)
			)
			(polygon
				(pts
					(xy 434.09489 -43.95978) (xy 434.09489 -43.45178) (xy 434.47589 -43.45178) (xy 434.47589 -43.95978)
				)
			)
		)
		(zone
			(layer "B.Cu")
			(hatch none 0.5)
			(connect_pads
				(clearance 0)
			)
			(min_thickness 0.25)
			(keepout
				(tracks not_allowed)
				(vias allowed)
				(pads allowed)
				(copperpour not_allowed)
				(footprints allowed)
			)
			(placement
				(enabled no)
				(sheetname "")
			)
			(fill
				(thermal_gap 0.5)
				(thermal_bridge_width 0.5)
				(island_removal_mode 0)
			)
			(polygon
				(pts
					(xy 434.47589 -43.95978) (xy 434.47589 -43.45178) (xy 434.09489 -43.45178) (xy 434.09489 -43.95978)
				)
			)
		)
	)
	(footprint ""
		(layer "B.Cu")
		(at 227.584 -93.345 90)
		(property "Reference" "R5N1"
			(at 0 0 90)
			(layer "B.SilkS")
			(hide yes)
			(effects
				(font
					(size 1.27 1.27)
				)
				(justify mirror)
			)
		)
		(property "Value" ""
			(at 0 0 90)
			(layer "B.Fab")
			(effects
				(font
					(size 1.27 1.27)
				)
				(justify mirror)
			)
		)
		(duplicate_pad_numbers_are_jumpers no)
		(fp_poly
			(pts
				(xy 0.2794 -0.1016) (xy -0.2794 -0.1016) (xy -0.2794 0.9906) (xy 0.2794 0.9906)
			)
			(stroke
				(width 0)
				(type default)
			)
			(fill no)
			(layer "B.CrtYd")
		)
		(fp_line
			(start 0.2794 -0.1016)
			(end 0.2794 0.9906)
			(stroke
				(width 0.1)
				(type default)
			)
			(layer "B.Fab")
		)
		(fp_line
			(start -0.2794 -0.1016)
			(end 0.2794 -0.1016)
			(stroke
				(width 0.1)
				(type default)
			)
			(layer "B.Fab")
		)
		(fp_line
			(start 0.2794 0.9906)
			(end -0.2794 0.9906)
			(stroke
				(width 0.1)
				(type default)
			)
			(layer "B.Fab")
		)
		(fp_line
			(start -0.2794 0.9906)
			(end -0.2794 -0.1016)
			(stroke
				(width 0.1)
				(type default)
			)
			(layer "B.Fab")
		)
		(pad "1" smd rect
			(at 0 0 270)
			(size 0.508 0.508)
			(layers "B.Cu" "B.Mask" "B.Paste")
			(net "P3V3_STBY")
		)
		(pad "2" smd rect
			(at 0 0.889 270)
			(size 0.508 0.508)
			(layers "B.Cu" "B.Mask" "B.Paste")
			(net "FM_CPU0_PKGID0")
		)
		(zone
			(layer "B.Cu")
			(hatch none 0.5)
			(connect_pads
				(clearance 0)
			)
			(min_thickness 0.25)
			(keepout
				(tracks allowed)
				(vias not_allowed)
				(pads allowed)
				(copperpour not_allowed)
				(footprints allowed)
			)
			(placement
				(enabled no)
				(sheetname "")
			)
			(fill
				(thermal_gap 0.5)
				(thermal_bridge_width 0.5)
				(island_removal_mode 0)
			)
			(polygon
				(pts
					(xy 227.838 -93.599) (xy 227.838 -93.091) (xy 228.219 -93.091) (xy 228.219 -93.599)
				)
			)
		)
		(zone
			(layer "B.Cu")
			(hatch none 0.5)
			(connect_pads
				(clearance 0)
			)
			(min_thickness 0.25)
			(keepout
				(tracks not_allowed)
				(vias allowed)
				(pads allowed)
				(copperpour not_allowed)
				(footprints allowed)
			)
			(placement
				(enabled no)
				(sheetname "")
			)
			(fill
				(thermal_gap 0.5)
				(thermal_bridge_width 0.5)
				(island_removal_mode 0)
			)
			(polygon
				(pts
					(xy 228.219 -93.599) (xy 228.219 -93.091) (xy 227.838 -93.091) (xy 227.838 -93.599)
				)
			)
		)
	)
)
